(kicad_pcb
	(version 20260206)
	(generator "pcbnew")
	(generator_version "10.0")
	(general
		(thickness 1.6)
		(legacy_teardrops no)
	)
	(paper "A4")
	(title_block
		(title "01162023_DA0F0TEBIF0_F0T_Expander_BD_F_brd_V02_OCP.brd")
		(comment 1 "Grand Teton / footprints 7208-7214 of 9728")
	)
	(layers
		(0 "F.Cu" signal "TOP")
		(4 "In1.Cu" signal "GND")
		(6 "In2.Cu" signal "VCC")
		(8 "In3.Cu" signal "VCC1")
		(10 "In4.Cu" signal "GND1")
		(12 "In5.Cu" signal "IN1")
		(14 "In6.Cu" signal "GND2")
		(16 "In7.Cu" signal "IN2")
		(18 "In8.Cu" signal "GND3")
		(20 "In9.Cu" signal "IN3")
		(22 "In10.Cu" signal "GND4")
		(24 "In11.Cu" signal "IN4")
		(26 "In12.Cu" signal "GND5")
		(28 "In13.Cu" signal "IN5")
		(30 "In14.Cu" signal "GND6")
		(32 "In15.Cu" signal "IN6")
		(34 "In16.Cu" signal "GND7")
		(2 "B.Cu" signal "BOTTOM")
		(9 "F.Adhes" user "F.Adhesive")
		(11 "B.Adhes" user "B.Adhesive")
		(13 "F.Paste" user "Package Geometry/Pastemask Top")
		(15 "B.Paste" user "Package Geometry/Pastemask Bottom")
		(5 "F.SilkS" user "Ref Des/Silkscreen Top")
		(7 "B.SilkS" user "Ref Des/Silkscreen Bottom")
		(1 "F.Mask" user "Board Geometry/Soldermask Top")
		(3 "B.Mask" user "Board Geometry/Soldermask Bottom")
		(17 "Dwgs.User" user "User.Drawings")
		(19 "Cmts.User" user "User.Comments")
		(21 "Eco1.User" user "User.Eco1")
		(23 "Eco2.User" user "User.Eco2")
		(25 "Edge.Cuts" user "Board Geometry/Outline")
		(27 "Margin" user)
		(31 "F.CrtYd" user "Package Geometry/Place Bound Top")
		(29 "B.CrtYd" user "Package Geometry/Place Bound Bottom")
		(35 "F.Fab" user "Ref Des/Assembly Top")
		(33 "B.Fab" user "Ref Des/Assembly Bottom")
	)
	(footprint ""
		(layer "B.Cu")
		(at 235.871512 -234.728004 90)
		(property "Reference" "R6196"
			(at 0 0 90)
			(layer "B.SilkS")
			(hide yes)
			(effects
				(font
					(size 1.27 1.27)
				)
				(justify mirror)
			)
		)
		(property "Value" ""
			(at 0 0 90)
			(layer "B.Fab")
			(effects
				(font
					(size 1.27 1.27)
				)
				(justify mirror)
			)
		)
		(duplicate_pad_numbers_are_jumpers no)
		(fp_line
			(start 0.7874 -0.4064)
			(end -0.7874 -0.4064)
			(stroke
				(width 0.1524)
				(type default)
			)
			(layer "B.SilkS")
		)
		(fp_line
			(start -0.7874 -0.4064)
			(end -0.7874 0.4064)
			(stroke
				(width 0.1524)
				(type default)
			)
			(layer "B.SilkS")
		)
		(fp_line
			(start 0.7874 0.4064)
			(end 0.7874 -0.4064)
			(stroke
				(width 0.1524)
				(type default)
			)
			(layer "B.SilkS")
		)
		(fp_line
			(start -0.7874 0.4064)
			(end 0.7874 0.4064)
			(stroke
				(width 0.1524)
				(type default)
			)
			(layer "B.SilkS")
		)
		(fp_line
			(start 0.67945 -0.305054)
			(end 0.12065 -0.305054)
			(stroke
				(width 0.1)
				(type default)
			)
			(layer "B.Fab")
		)
		(fp_line
			(start 0.12065 -0.305054)
			(end 0.12065 -0.2794)
			(stroke
				(width 0.1)
				(type default)
			)
			(layer "B.Fab")
		)
		(fp_line
			(start -0.12065 -0.3048)
			(end -0.67945 -0.3048)
			(stroke
				(width 0.1)
				(type default)
			)
			(layer "B.Fab")
		)
		(fp_line
			(start -0.67945 -0.3048)
			(end -0.67945 0.3048)
			(stroke
				(width 0.1)
				(type default)
			)
			(layer "B.Fab")
		)
		(fp_line
			(start 0.12065 -0.2794)
			(end -0.12065 -0.2794)
			(stroke
				(width 0.1)
				(type default)
			)
			(layer "B.Fab")
		)
		(fp_line
			(start -0.12065 -0.2794)
			(end -0.12065 -0.3048)
			(stroke
				(width 0.1)
				(type default)
			)
			(layer "B.Fab")
		)
		(fp_line
			(start 0.12065 0.2794)
			(end 0.12065 0.3048)
			(stroke
				(width 0.1)
				(type default)
			)
			(layer "B.Fab")
		)
		(fp_line
			(start -0.120396 0.2794)
			(end 0.12065 0.2794)
			(stroke
				(width 0.1)
				(type default)
			)
			(layer "B.Fab")
		)
		(fp_line
			(start 0.67945 0.3048)
			(end 0.67945 -0.305054)
			(stroke
				(width 0.1)
				(type default)
			)
			(layer "B.Fab")
		)
		(fp_line
			(start 0.12065 0.3048)
			(end 0.67945 0.3048)
			(stroke
				(width 0.1)
				(type default)
			)
			(layer "B.Fab")
		)
		(fp_line
			(start -0.120396 0.3048)
			(end -0.120396 0.2794)
			(stroke
				(width 0.1)
				(type default)
			)
			(layer "B.Fab")
		)
		(fp_line
			(start -0.67945 0.3048)
			(end -0.120396 0.3048)
			(stroke
				(width 0.1)
				(type default)
			)
			(layer "B.Fab")
		)
		(pad "1" smd circle
			(at 0.40005 0 270)
			(size 0 0)
			(layers "B.Cu" "B.Mask" "B.Paste")
			(net "GND")
		)
		(pad "2" smd circle
			(at -0.40005 0 270)
			(size 0 0)
			(layers "B.Cu" "B.Mask" "B.Paste")
			(net "SSD14_PWRDIS_BIC_R")
		)
	)
	(footprint ""
		(layer "B.Cu")
		(at 4.880102 -285.910782)
		(property "Reference" "PC214"
			(at 0 0 0)
			(layer "B.SilkS")
			(hide yes)
			(effects
				(font
					(size 1.27 1.27)
				)
				(justify mirror)
			)
		)
		(property "Value" ""
			(at 0 0 0)
			(layer "B.Fab")
			(effects
				(font
					(size 1.27 1.27)
				)
				(justify mirror)
			)
		)
		(duplicate_pad_numbers_are_jumpers no)
		(fp_line
			(start -1.524 -0.762)
			(end -1.524 0.762)
			(stroke
				(width 0.1524)
				(type default)
			)
			(layer "B.SilkS")
		)
		(fp_line
			(start -1.524 0.762)
			(end 1.524 0.762)
			(stroke
				(width 0.1524)
				(type default)
			)
			(layer "B.SilkS")
		)
		(fp_line
			(start 1.524 -0.762)
			(end -1.524 -0.762)
			(stroke
				(width 0.1524)
				(type default)
			)
			(layer "B.SilkS")
		)
		(fp_line
			(start 1.524 0.762)
			(end 1.524 -0.762)
			(stroke
				(width 0.1524)
				(type default)
			)
			(layer "B.SilkS")
		)
		(fp_line
			(start -1.1049 -0.724916)
			(end 1.1049 -0.724916)
			(stroke
				(width 0.1)
				(type default)
			)
			(layer "B.Fab")
		)
		(fp_line
			(start -1.1049 0.724916)
			(end -1.1049 -0.724916)
			(stroke
				(width 0.1)
				(type default)
			)
			(layer "B.Fab")
		)
		(fp_line
			(start 1.1049 -0.724916)
			(end 1.1049 0.724916)
			(stroke
				(width 0.1)
				(type default)
			)
			(layer "B.Fab")
		)
		(fp_line
			(start 1.1049 0.724916)
			(end -1.1049 0.724916)
			(stroke
				(width 0.1)
				(type default)
			)
			(layer "B.Fab")
		)
		(pad "1" smd rect
			(at 0.889 0)
			(size 1.016 1.27)
			(layers "B.Cu" "B.Mask" "B.Paste")
			(net "P1V25_PEX0_R")
		)
		(pad "2" smd rect
			(at -0.889 0)
			(size 1.016 1.27)
			(layers "B.Cu" "B.Mask" "B.Paste")
			(net "GND")
		)
	)
	(footprint ""
		(layer "B.Cu")
		(at 134.808214 -212.381846 180)
		(property "Reference" "R983"
			(at 0 0 0)
			(layer "B.SilkS")
			(hide yes)
			(effects
				(font
					(size 1.27 1.27)
				)
				(justify mirror)
			)
		)
		(property "Value" ""
			(at 0 0 0)
			(layer "B.Fab")
			(effects
				(font
					(size 1.27 1.27)
				)
				(justify mirror)
			)
		)
		(duplicate_pad_numbers_are_jumpers no)
		(fp_line
			(start 0.7874 0.4064)
			(end 0.7874 -0.4064)
			(stroke
				(width 0.1524)
				(type default)
			)
			(layer "B.SilkS")
		)
		(fp_line
			(start 0.7874 -0.4064)
			(end -0.7874 -0.4064)
			(stroke
				(width 0.1524)
				(type default)
			)
			(layer "B.SilkS")
		)
		(fp_line
			(start -0.7874 0.4064)
			(end 0.7874 0.4064)
			(stroke
				(width 0.1524)
				(type default)
			)
			(layer "B.SilkS")
		)
		(fp_line
			(start -0.7874 -0.4064)
			(end -0.7874 0.4064)
			(stroke
				(width 0.1524)
				(type default)
			)
			(layer "B.SilkS")
		)
		(fp_line
			(start 0.67945 0.3048)
			(end 0.67945 -0.305054)
			(stroke
				(width 0.1)
				(type default)
			)
			(layer "B.Fab")
		)
		(fp_line
			(start 0.67945 -0.305054)
			(end 0.12065 -0.305054)
			(stroke
				(width 0.1)
				(type default)
			)
			(layer "B.Fab")
		)
		(fp_line
			(start 0.12065 0.3048)
			(end 0.67945 0.3048)
			(stroke
				(width 0.1)
				(type default)
			)
			(layer "B.Fab")
		)
		(fp_line
			(start 0.12065 0.2794)
			(end 0.12065 0.3048)
			(stroke
				(width 0.1)
				(type default)
			)
			(layer "B.Fab")
		)
		(fp_line
			(start 0.12065 -0.2794)
			(end -0.12065 -0.2794)
			(stroke
				(width 0.1)
				(type default)
			)
			(layer "B.Fab")
		)
		(fp_line
			(start 0.12065 -0.305054)
			(end 0.12065 -0.2794)
			(stroke
				(width 0.1)
				(type default)
			)
			(layer "B.Fab")
		)
		(fp_line
			(start -0.120396 0.3048)
			(end -0.120396 0.2794)
			(stroke
				(width 0.1)
				(type default)
			)
			(layer "B.Fab")
		)
		(fp_line
			(start -0.120396 0.2794)
			(end 0.12065 0.2794)
			(stroke
				(width 0.1)
				(type default)
			)
			(layer "B.Fab")
		)
		(fp_line
			(start -0.12065 -0.2794)
			(end -0.12065 -0.3048)
			(stroke
				(width 0.1)
				(type default)
			)
			(layer "B.Fab")
		)
		(fp_line
			(start -0.12065 -0.3048)
			(end -0.67945 -0.3048)
			(stroke
				(width 0.1)
				(type default)
			)
			(layer "B.Fab")
		)
		(fp_line
			(start -0.67945 0.3048)
			(end -0.120396 0.3048)
			(stroke
				(width 0.1)
				(type default)
			)
			(layer "B.Fab")
		)
		(fp_line
			(start -0.67945 -0.3048)
			(end -0.67945 0.3048)
			(stroke
				(width 0.1)
				(type default)
			)
			(layer "B.Fab")
		)
		(pad "1" smd circle
			(at 0.40005 0)
			(size 0 0)
			(layers "B.Cu" "B.Mask" "B.Paste")
			(net "UART_PEX1_CLI_BUF_TX")
		)
		(pad "2" smd circle
			(at -0.40005 0)
			(size 0 0)
			(layers "B.Cu" "B.Mask" "B.Paste")
			(net "P3V3_AUX")
		)
	)
	(footprint ""
		(layer "B.Cu")
		(at 296.599864 -290.199826 90)
		(property "Reference" "C1738"
			(at 0 0 90)
			(layer "B.SilkS")
			(hide yes)
			(effects
				(font
					(size 1.27 1.27)
				)
				(justify mirror)
			)
		)
		(property "Value" ""
			(at 0 0 90)
			(layer "B.Fab")
			(effects
				(font
					(size 1.27 1.27)
				)
				(justify mirror)
			)
		)
		(duplicate_pad_numbers_are_jumpers no)
		(fp_line
			(start 0.299974 -0.150114)
			(end -0.299974 -0.150114)
			(stroke
				(width 0.1)
				(type default)
			)
			(layer "B.Fab")
		)
		(fp_line
			(start -0.299974 -0.150114)
			(end -0.299974 0.150114)
			(stroke
				(width 0.1)
				(type default)
			)
			(layer "B.Fab")
		)
		(fp_line
			(start 0.299974 0.150114)
			(end 0.299974 -0.150114)
			(stroke
				(width 0.1)
				(type default)
			)
			(layer "B.Fab")
		)
		(fp_line
			(start -0.299974 0.150114)
			(end 0.299974 0.150114)
			(stroke
				(width 0.1)
				(type default)
			)
			(layer "B.Fab")
		)
		(pad "1" smd rect
			(at 0.2667 0 270)
			(size 0.3048 0.381)
			(layers "B.Cu" "B.Mask" "B.Paste")
			(net "P0V8_SERDES_VDDA_PEX2")
		)
		(pad "2" smd rect
			(at -0.2667 0 270)
			(size 0.3048 0.381)
			(layers "B.Cu" "B.Mask" "B.Paste")
			(net "GND")
		)
	)
	(footprint ""
		(layer "B.Cu")
		(at 128.41097 -176.08423)
		(property "Reference" "C2655"
			(at 0 0 0)
			(layer "B.SilkS")
			(hide yes)
			(effects
				(font
					(size 1.27 1.27)
				)
				(justify mirror)
			)
		)
		(property "Value" ""
			(at 0 0 0)
			(layer "B.Fab")
			(effects
				(font
					(size 1.27 1.27)
				)
				(justify mirror)
			)
		)
		(duplicate_pad_numbers_are_jumpers no)
		(fp_line
			(start -1.2954 -0.5842)
			(end -1.2954 0.5842)
			(stroke
				(width 0.1524)
				(type default)
			)
			(layer "B.SilkS")
		)
		(fp_line
			(start -1.2954 0.5842)
			(end 1.2954 0.5842)
			(stroke
				(width 0.1524)
				(type default)
			)
			(layer "B.SilkS")
		)
		(fp_line
			(start 1.2954 -0.5842)
			(end -1.2954 -0.5842)
			(stroke
				(width 0.1524)
				(type default)
			)
			(layer "B.SilkS")
		)
		(fp_line
			(start 1.2954 0.5842)
			(end 1.2954 -0.5842)
			(stroke
				(width 0.1524)
				(type default)
			)
			(layer "B.SilkS")
		)
		(fp_line
			(start -1.1938 -0.4064)
			(end -1.1938 0.4064)
			(stroke
				(width 0.1)
				(type default)
			)
			(layer "B.Fab")
		)
		(fp_line
			(start -1.1938 0.4064)
			(end -0.8636 0.4064)
			(stroke
				(width 0.1)
				(type default)
			)
			(layer "B.Fab")
		)
		(fp_line
			(start -0.8636 -0.4572)
			(end -0.8636 -0.4064)
			(stroke
				(width 0.1)
				(type default)
			)
			(layer "B.Fab")
		)
		(fp_line
			(start -0.8636 -0.4064)
			(end -1.1938 -0.4064)
			(stroke
				(width 0.1)
				(type default)
			)
			(layer "B.Fab")
		)
		(fp_line
			(start -0.8636 0.4064)
			(end -0.8636 0.4572)
			(stroke
				(width 0.1)
				(type default)
			)
			(layer "B.Fab")
		)
		(fp_line
			(start -0.8636 0.4572)
			(end 0.8636 0.4572)
			(stroke
				(width 0.1)
				(type default)
			)
			(layer "B.Fab")
		)
		(fp_line
			(start 0.8636 -0.4572)
			(end -0.8636 -0.4572)
			(stroke
				(width 0.1)
				(type default)
			)
			(layer "B.Fab")
		)
		(fp_line
			(start 0.8636 -0.4064)
			(end 0.8636 -0.4572)
			(stroke
				(width 0.1)
				(type default)
			)
			(layer "B.Fab")
		)
		(fp_line
			(start 0.8636 0.4064)
			(end 1.1938 0.4064)
			(stroke
				(width 0.1)
				(type default)
			)
			(layer "B.Fab")
		)
		(fp_line
			(start 0.8636 0.4572)
			(end 0.8636 0.4064)
			(stroke
				(width 0.1)
				(type default)
			)
			(layer "B.Fab")
		)
		(fp_line
			(start 1.1938 -0.4064)
			(end 0.8636 -0.4064)
			(stroke
				(width 0.1)
				(type default)
			)
			(layer "B.Fab")
		)
		(fp_line
			(start 1.1938 0.4064)
			(end 1.1938 -0.4064)
			(stroke
				(width 0.1)
				(type default)
			)
			(layer "B.Fab")
		)
		(pad "1" smd rect
			(at 0.7366 0 270)
			(size 0.7112 0.8128)
			(layers "B.Cu" "B.Mask" "B.Paste")
			(net "P3V3_DB2000QL_VDDR")
		)
		(pad "2" smd rect
			(at -0.7366 0 270)
			(size 0.7112 0.8128)
			(layers "B.Cu" "B.Mask" "B.Paste")
			(net "GND")
		)
	)
	(footprint ""
		(layer "B.Cu")
		(at 309.741824 -100.056696 180)
		(property "Reference" "R281"
			(at 0 0 0)
			(layer "B.SilkS")
			(hide yes)
			(effects
				(font
					(size 1.27 1.27)
				)
				(justify mirror)
			)
		)
		(property "Value" ""
			(at 0 0 0)
			(layer "B.Fab")
			(effects
				(font
					(size 1.27 1.27)
				)
				(justify mirror)
			)
		)
		(duplicate_pad_numbers_are_jumpers no)
		(fp_line
			(start 0.7874 0.4064)
			(end 0.7874 -0.4064)
			(stroke
				(width 0.1524)
				(type default)
			)
			(layer "B.SilkS")
		)
		(fp_line
			(start 0.7874 -0.4064)
			(end -0.7874 -0.4064)
			(stroke
				(width 0.1524)
				(type default)
			)
			(layer "B.SilkS")
		)
		(fp_line
			(start -0.7874 0.4064)
			(end 0.7874 0.4064)
			(stroke
				(width 0.1524)
				(type default)
			)
			(layer "B.SilkS")
		)
		(fp_line
			(start -0.7874 -0.4064)
			(end -0.7874 0.4064)
			(stroke
				(width 0.1524)
				(type default)
			)
			(layer "B.SilkS")
		)
		(fp_line
			(start 0.67945 0.3048)
			(end 0.67945 -0.305054)
			(stroke
				(width 0.1)
				(type default)
			)
			(layer "B.Fab")
		)
		(fp_line
			(start 0.67945 -0.305054)
			(end 0.12065 -0.305054)
			(stroke
				(width 0.1)
				(type default)
			)
			(layer "B.Fab")
		)
		(fp_line
			(start 0.12065 0.3048)
			(end 0.67945 0.3048)
			(stroke
				(width 0.1)
				(type default)
			)
			(layer "B.Fab")
		)
		(fp_line
			(start 0.12065 0.2794)
			(end 0.12065 0.3048)
			(stroke
				(width 0.1)
				(type default)
			)
			(layer "B.Fab")
		)
		(fp_line
			(start 0.12065 -0.2794)
			(end -0.12065 -0.2794)
			(stroke
				(width 0.1)
				(type default)
			)
			(layer "B.Fab")
		)
		(fp_line
			(start 0.12065 -0.305054)
			(end 0.12065 -0.2794)
			(stroke
				(width 0.1)
				(type default)
			)
			(layer "B.Fab")
		)
		(fp_line
			(start -0.120396 0.3048)
			(end -0.120396 0.2794)
			(stroke
				(width 0.1)
				(type default)
			)
			(layer "B.Fab")
		)
		(fp_line
			(start -0.120396 0.2794)
			(end 0.12065 0.2794)
			(stroke
				(width 0.1)
				(type default)
			)
			(layer "B.Fab")
		)
		(fp_line
			(start -0.12065 -0.2794)
			(end -0.12065 -0.3048)
			(stroke
				(width 0.1)
				(type default)
			)
			(layer "B.Fab")
		)
		(fp_line
			(start -0.12065 -0.3048)
			(end -0.67945 -0.3048)
			(stroke
				(width 0.1)
				(type default)
			)
			(layer "B.Fab")
		)
		(fp_line
			(start -0.67945 0.3048)
			(end -0.120396 0.3048)
			(stroke
				(width 0.1)
				(type default)
			)
			(layer "B.Fab")
		)
		(fp_line
			(start -0.67945 -0.3048)
			(end -0.67945 0.3048)
			(stroke
				(width 0.1)
				(type default)
			)
			(layer "B.Fab")
		)
		(pad "1" smd circle
			(at 0.40005 0)
			(size 0 0)
			(layers "B.Cu" "B.Mask" "B.Paste")
			(net "NIC5_SLOT_ID0")
		)
		(pad "2" smd circle
			(at -0.40005 0)
			(size 0 0)
			(layers "B.Cu" "B.Mask" "B.Paste")
			(net "GND")
		)
	)
	(footprint ""
		(layer "B.Cu")
		(at 52.999894 -290.199826 90)
		(property "Reference" "C1186"
			(at 0 0 90)
			(layer "B.SilkS")
			(hide yes)
			(effects
				(font
					(size 1.27 1.27)
				)
				(justify mirror)
			)
		)
		(property "Value" ""
			(at 0 0 90)
			(layer "B.Fab")
			(effects
				(font
					(size 1.27 1.27)
				)
				(justify mirror)
			)
		)
		(duplicate_pad_numbers_are_jumpers no)
		(fp_line
			(start 0.299974 -0.150114)
			(end -0.299974 -0.150114)
			(stroke
				(width 0.1)
				(type default)
			)
			(layer "B.Fab")
		)
		(fp_line
			(start -0.299974 -0.150114)
			(end -0.299974 0.150114)
			(stroke
				(width 0.1)
				(type default)
			)
			(layer "B.Fab")
		)
		(fp_line
			(start 0.299974 0.150114)
			(end 0.299974 -0.150114)
			(stroke
				(width 0.1)
				(type default)
			)
			(layer "B.Fab")
		)
		(fp_line
			(start -0.299974 0.150114)
			(end 0.299974 0.150114)
			(stroke
				(width 0.1)
				(type default)
			)
			(layer "B.Fab")
		)
		(pad "1" smd rect
			(at 0.2667 0 270)
			(size 0.3048 0.381)
			(layers "B.Cu" "B.Mask" "B.Paste")
			(net "P0V8_SERDES_VDDA_PEX0")
		)
		(pad "2" smd rect
			(at -0.2667 0 270)
			(size 0.3048 0.381)
			(layers "B.Cu" "B.Mask" "B.Paste")
			(net "GND")
		)
	)
)
